(kicad_pcb
	(version 20260206)
	(generator "pcbnew")
	(generator_version "10.0")
	(general
		(thickness 1.6)
		(legacy_teardrops no)
	)
	(paper "A4")
	(title_block
		(title "01162023_DA0F0TEBIF0_F0T_Expander_BD_F_brd_V02_OCP.brd")
		(comment 1 "Grand Teton / footprints 7926-7935 of 9728")
	)
	(layers
		(0 "F.Cu" signal "TOP")
		(4 "In1.Cu" signal "GND")
		(6 "In2.Cu" signal "VCC")
		(8 "In3.Cu" signal "VCC1")
		(10 "In4.Cu" signal "GND1")
		(12 "In5.Cu" signal "IN1")
		(14 "In6.Cu" signal "GND2")
		(16 "In7.Cu" signal "IN2")
		(18 "In8.Cu" signal "GND3")
		(20 "In9.Cu" signal "IN3")
		(22 "In10.Cu" signal "GND4")
		(24 "In11.Cu" signal "IN4")
		(26 "In12.Cu" signal "GND5")
		(28 "In13.Cu" signal "IN5")
		(30 "In14.Cu" signal "GND6")
		(32 "In15.Cu" signal "IN6")
		(34 "In16.Cu" signal "GND7")
		(2 "B.Cu" signal "BOTTOM")
		(9 "F.Adhes" user "F.Adhesive")
		(11 "B.Adhes" user "B.Adhesive")
		(13 "F.Paste" user "Package Geometry/Pastemask Top")
		(15 "B.Paste" user "Package Geometry/Pastemask Bottom")
		(5 "F.SilkS" user "Ref Des/Silkscreen Top")
		(7 "B.SilkS" user "Ref Des/Silkscreen Bottom")
		(1 "F.Mask" user "Board Geometry/Soldermask Top")
		(3 "B.Mask" user "Board Geometry/Soldermask Bottom")
		(17 "Dwgs.User" user "User.Drawings")
		(19 "Cmts.User" user "User.Comments")
		(21 "Eco1.User" user "User.Eco1")
		(23 "Eco2.User" user "User.Eco2")
		(25 "Edge.Cuts" user "Board Geometry/Outline")
		(27 "Margin" user)
		(31 "F.CrtYd" user "Package Geometry/Place Bound Top")
		(29 "B.CrtYd" user "Package Geometry/Place Bound Bottom")
		(35 "F.Fab" user "Ref Des/Assembly Top")
		(33 "B.Fab" user "Ref Des/Assembly Bottom")
	)
	(footprint ""
		(layer "B.Cu")
		(at 224.08261 -279.57907 180)
		(property "Reference" "C4278"
			(at 0 0 0)
			(layer "B.SilkS")
			(hide yes)
			(effects
				(font
					(size 1.27 1.27)
				)
				(justify mirror)
			)
		)
		(property "Value" ""
			(at 0 0 0)
			(layer "B.Fab")
			(effects
				(font
					(size 1.27 1.27)
				)
				(justify mirror)
			)
		)
		(duplicate_pad_numbers_are_jumpers no)
		(fp_line
			(start 0.299974 0.150114)
			(end 0.299974 -0.150114)
			(stroke
				(width 0.1)
				(type default)
			)
			(layer "B.Fab")
		)
		(fp_line
			(start 0.299974 -0.150114)
			(end -0.299974 -0.150114)
			(stroke
				(width 0.1)
				(type default)
			)
			(layer "B.Fab")
		)
		(fp_line
			(start -0.299974 0.150114)
			(end 0.299974 0.150114)
			(stroke
				(width 0.1)
				(type default)
			)
			(layer "B.Fab")
		)
		(fp_line
			(start -0.299974 -0.150114)
			(end -0.299974 0.150114)
			(stroke
				(width 0.1)
				(type default)
			)
			(layer "B.Fab")
		)
		(pad "1" smd rect
			(at 0.2667 0)
			(size 0.3048 0.381)
			(layers "B.Cu" "B.Mask" "B.Paste")
			(net "P1V25_PEX1")
		)
		(pad "2" smd rect
			(at -0.2667 0)
			(size 0.3048 0.381)
			(layers "B.Cu" "B.Mask" "B.Paste")
			(net "GND")
		)
	)
	(footprint ""
		(layer "B.Cu")
		(at 400.349974 -299.699934 -90)
		(property "Reference" "C1956"
			(at 0 0 90)
			(layer "B.SilkS")
			(hide yes)
			(effects
				(font
					(size 1.27 1.27)
				)
				(justify mirror)
			)
		)
		(property "Value" ""
			(at 0 0 90)
			(layer "B.Fab")
			(effects
				(font
					(size 1.27 1.27)
				)
				(justify mirror)
			)
		)
		(duplicate_pad_numbers_are_jumpers no)
		(fp_line
			(start -0.299974 0.150114)
			(end 0.299974 0.150114)
			(stroke
				(width 0.1)
				(type default)
			)
			(layer "B.Fab")
		)
		(fp_line
			(start 0.299974 0.150114)
			(end 0.299974 -0.150114)
			(stroke
				(width 0.1)
				(type default)
			)
			(layer "B.Fab")
		)
		(fp_line
			(start -0.299974 -0.150114)
			(end -0.299974 0.150114)
			(stroke
				(width 0.1)
				(type default)
			)
			(layer "B.Fab")
		)
		(fp_line
			(start 0.299974 -0.150114)
			(end -0.299974 -0.150114)
			(stroke
				(width 0.1)
				(type default)
			)
			(layer "B.Fab")
		)
		(pad "1" smd rect
			(at 0.2667 0 90)
			(size 0.3048 0.381)
			(layers "B.Cu" "B.Mask" "B.Paste")
			(net "P0V8_SERDES_VDDA_PEX3")
		)
		(pad "2" smd rect
			(at -0.2667 0 90)
			(size 0.3048 0.381)
			(layers "B.Cu" "B.Mask" "B.Paste")
			(net "GND")
		)
	)
	(footprint ""
		(layer "B.Cu")
		(at 406.999948 -299.699934 -90)
		(property "Reference" "C1964"
			(at 0 0 90)
			(layer "B.SilkS")
			(hide yes)
			(effects
				(font
					(size 1.27 1.27)
				)
				(justify mirror)
			)
		)
		(property "Value" ""
			(at 0 0 90)
			(layer "B.Fab")
			(effects
				(font
					(size 1.27 1.27)
				)
				(justify mirror)
			)
		)
		(duplicate_pad_numbers_are_jumpers no)
		(fp_line
			(start -0.299974 0.150114)
			(end 0.299974 0.150114)
			(stroke
				(width 0.1)
				(type default)
			)
			(layer "B.Fab")
		)
		(fp_line
			(start 0.299974 0.150114)
			(end 0.299974 -0.150114)
			(stroke
				(width 0.1)
				(type default)
			)
			(layer "B.Fab")
		)
		(fp_line
			(start -0.299974 -0.150114)
			(end -0.299974 0.150114)
			(stroke
				(width 0.1)
				(type default)
			)
			(layer "B.Fab")
		)
		(fp_line
			(start 0.299974 -0.150114)
			(end -0.299974 -0.150114)
			(stroke
				(width 0.1)
				(type default)
			)
			(layer "B.Fab")
		)
		(pad "1" smd rect
			(at 0.2667 0 90)
			(size 0.3048 0.381)
			(layers "B.Cu" "B.Mask" "B.Paste")
			(net "P0V8_SERDES_VDDA_PEX3")
		)
		(pad "2" smd rect
			(at -0.2667 0 90)
			(size 0.3048 0.381)
			(layers "B.Cu" "B.Mask" "B.Paste")
			(net "GND")
		)
	)
	(footprint ""
		(layer "B.Cu")
		(at 365.931196 -283.818584 90)
		(property "Reference" "PR160"
			(at 0 0 90)
			(layer "B.SilkS")
			(hide yes)
			(effects
				(font
					(size 1.27 1.27)
				)
				(justify mirror)
			)
		)
		(property "Value" ""
			(at 0 0 90)
			(layer "B.Fab")
			(effects
				(font
					(size 1.27 1.27)
				)
				(justify mirror)
			)
		)
		(duplicate_pad_numbers_are_jumpers no)
		(fp_line
			(start 0.7874 -0.4064)
			(end -0.7874 -0.4064)
			(stroke
				(width 0.1524)
				(type default)
			)
			(layer "B.SilkS")
		)
		(fp_line
			(start -0.7874 -0.4064)
			(end -0.7874 0.4064)
			(stroke
				(width 0.1524)
				(type default)
			)
			(layer "B.SilkS")
		)
		(fp_line
			(start 0.7874 0.4064)
			(end 0.7874 -0.4064)
			(stroke
				(width 0.1524)
				(type default)
			)
			(layer "B.SilkS")
		)
		(fp_line
			(start -0.7874 0.4064)
			(end 0.7874 0.4064)
			(stroke
				(width 0.1524)
				(type default)
			)
			(layer "B.SilkS")
		)
		(fp_line
			(start 0.67945 -0.305054)
			(end 0.12065 -0.305054)
			(stroke
				(width 0.1)
				(type default)
			)
			(layer "B.Fab")
		)
		(fp_line
			(start 0.12065 -0.305054)
			(end 0.12065 -0.2794)
			(stroke
				(width 0.1)
				(type default)
			)
			(layer "B.Fab")
		)
		(fp_line
			(start -0.12065 -0.3048)
			(end -0.67945 -0.3048)
			(stroke
				(width 0.1)
				(type default)
			)
			(layer "B.Fab")
		)
		(fp_line
			(start -0.67945 -0.3048)
			(end -0.67945 0.3048)
			(stroke
				(width 0.1)
				(type default)
			)
			(layer "B.Fab")
		)
		(fp_line
			(start 0.12065 -0.2794)
			(end -0.12065 -0.2794)
			(stroke
				(width 0.1)
				(type default)
			)
			(layer "B.Fab")
		)
		(fp_line
			(start -0.12065 -0.2794)
			(end -0.12065 -0.3048)
			(stroke
				(width 0.1)
				(type default)
			)
			(layer "B.Fab")
		)
		(fp_line
			(start 0.12065 0.2794)
			(end 0.12065 0.3048)
			(stroke
				(width 0.1)
				(type default)
			)
			(layer "B.Fab")
		)
		(fp_line
			(start -0.120396 0.2794)
			(end 0.12065 0.2794)
			(stroke
				(width 0.1)
				(type default)
			)
			(layer "B.Fab")
		)
		(fp_line
			(start 0.67945 0.3048)
			(end 0.67945 -0.305054)
			(stroke
				(width 0.1)
				(type default)
			)
			(layer "B.Fab")
		)
		(fp_line
			(start 0.12065 0.3048)
			(end 0.67945 0.3048)
			(stroke
				(width 0.1)
				(type default)
			)
			(layer "B.Fab")
		)
		(fp_line
			(start -0.120396 0.3048)
			(end -0.120396 0.2794)
			(stroke
				(width 0.1)
				(type default)
			)
			(layer "B.Fab")
		)
		(fp_line
			(start -0.67945 0.3048)
			(end -0.120396 0.3048)
			(stroke
				(width 0.1)
				(type default)
			)
			(layer "B.Fab")
		)
		(pad "1" smd circle
			(at 0.40005 0 270)
			(size 0 0)
			(layers "B.Cu" "B.Mask" "B.Paste")
			(net "P0V8_PEX3_PVCC")
		)
		(pad "2" smd circle
			(at -0.40005 0 270)
			(size 0 0)
			(layers "B.Cu" "B.Mask" "B.Paste")
			(net "P0V8_PEX3_VCC2")
		)
	)
	(footprint ""
		(layer "B.Cu")
		(at 372.48211 -228.346 90)
		(property "Reference" "R3500"
			(at 0 0 90)
			(layer "B.SilkS")
			(hide yes)
			(effects
				(font
					(size 1.27 1.27)
				)
				(justify mirror)
			)
		)
		(property "Value" ""
			(at 0 0 90)
			(layer "B.Fab")
			(effects
				(font
					(size 1.27 1.27)
				)
				(justify mirror)
			)
		)
		(duplicate_pad_numbers_are_jumpers no)
		(fp_line
			(start 0.7874 -0.4064)
			(end -0.7874 -0.4064)
			(stroke
				(width 0.1524)
				(type default)
			)
			(layer "B.SilkS")
		)
		(fp_line
			(start -0.7874 -0.4064)
			(end -0.7874 0.4064)
			(stroke
				(width 0.1524)
				(type default)
			)
			(layer "B.SilkS")
		)
		(fp_line
			(start 0.7874 0.4064)
			(end 0.7874 -0.4064)
			(stroke
				(width 0.1524)
				(type default)
			)
			(layer "B.SilkS")
		)
		(fp_line
			(start -0.7874 0.4064)
			(end 0.7874 0.4064)
			(stroke
				(width 0.1524)
				(type default)
			)
			(layer "B.SilkS")
		)
		(fp_line
			(start 0.67945 -0.305054)
			(end 0.12065 -0.305054)
			(stroke
				(width 0.1)
				(type default)
			)
			(layer "B.Fab")
		)
		(fp_line
			(start 0.12065 -0.305054)
			(end 0.12065 -0.2794)
			(stroke
				(width 0.1)
				(type default)
			)
			(layer "B.Fab")
		)
		(fp_line
			(start -0.12065 -0.3048)
			(end -0.67945 -0.3048)
			(stroke
				(width 0.1)
				(type default)
			)
			(layer "B.Fab")
		)
		(fp_line
			(start -0.67945 -0.3048)
			(end -0.67945 0.3048)
			(stroke
				(width 0.1)
				(type default)
			)
			(layer "B.Fab")
		)
		(fp_line
			(start 0.12065 -0.2794)
			(end -0.12065 -0.2794)
			(stroke
				(width 0.1)
				(type default)
			)
			(layer "B.Fab")
		)
		(fp_line
			(start -0.12065 -0.2794)
			(end -0.12065 -0.3048)
			(stroke
				(width 0.1)
				(type default)
			)
			(layer "B.Fab")
		)
		(fp_line
			(start 0.12065 0.2794)
			(end 0.12065 0.3048)
			(stroke
				(width 0.1)
				(type default)
			)
			(layer "B.Fab")
		)
		(fp_line
			(start -0.120396 0.2794)
			(end 0.12065 0.2794)
			(stroke
				(width 0.1)
				(type default)
			)
			(layer "B.Fab")
		)
		(fp_line
			(start 0.67945 0.3048)
			(end 0.67945 -0.305054)
			(stroke
				(width 0.1)
				(type default)
			)
			(layer "B.Fab")
		)
		(fp_line
			(start 0.12065 0.3048)
			(end 0.67945 0.3048)
			(stroke
				(width 0.1)
				(type default)
			)
			(layer "B.Fab")
		)
		(fp_line
			(start -0.120396 0.3048)
			(end -0.120396 0.2794)
			(stroke
				(width 0.1)
				(type default)
			)
			(layer "B.Fab")
		)
		(fp_line
			(start -0.67945 0.3048)
			(end -0.120396 0.3048)
			(stroke
				(width 0.1)
				(type default)
			)
			(layer "B.Fab")
		)
		(pad "1" smd circle
			(at 0.40005 0 270)
			(size 0 0)
			(layers "B.Cu" "B.Mask" "B.Paste")
			(net "SPI_PEX3_CS_MUX_N")
		)
		(pad "2" smd circle
			(at -0.40005 0 270)
			(size 0 0)
			(layers "B.Cu" "B.Mask" "B.Paste")
			(net "SPI_PEX3_CS_MUX_R_N")
		)
	)
	(footprint ""
		(layer "B.Cu")
		(at 179.55006 -301.599854 -90)
		(property "Reference" "C1482"
			(at 0 0 90)
			(layer "B.SilkS")
			(hide yes)
			(effects
				(font
					(size 1.27 1.27)
				)
				(justify mirror)
			)
		)
		(property "Value" ""
			(at 0 0 90)
			(layer "B.Fab")
			(effects
				(font
					(size 1.27 1.27)
				)
				(justify mirror)
			)
		)
		(duplicate_pad_numbers_are_jumpers no)
		(fp_line
			(start -0.299974 0.150114)
			(end 0.299974 0.150114)
			(stroke
				(width 0.1)
				(type default)
			)
			(layer "B.Fab")
		)
		(fp_line
			(start 0.299974 0.150114)
			(end 0.299974 -0.150114)
			(stroke
				(width 0.1)
				(type default)
			)
			(layer "B.Fab")
		)
		(fp_line
			(start -0.299974 -0.150114)
			(end -0.299974 0.150114)
			(stroke
				(width 0.1)
				(type default)
			)
			(layer "B.Fab")
		)
		(fp_line
			(start 0.299974 -0.150114)
			(end -0.299974 -0.150114)
			(stroke
				(width 0.1)
				(type default)
			)
			(layer "B.Fab")
		)
		(pad "1" smd rect
			(at 0.2667 0 90)
			(size 0.3048 0.381)
			(layers "B.Cu" "B.Mask" "B.Paste")
			(net "P0V8_SERDES_VDDA_PEX1")
		)
		(pad "2" smd rect
			(at -0.2667 0 90)
			(size 0.3048 0.381)
			(layers "B.Cu" "B.Mask" "B.Paste")
			(net "GND")
		)
	)
	(footprint ""
		(layer "B.Cu")
		(at 415.549842 -288.299906 90)
		(property "Reference" "C3441"
			(at 0 0 90)
			(layer "B.SilkS")
			(hide yes)
			(effects
				(font
					(size 1.27 1.27)
				)
				(justify mirror)
			)
		)
		(property "Value" ""
			(at 0 0 90)
			(layer "B.Fab")
			(effects
				(font
					(size 1.27 1.27)
				)
				(justify mirror)
			)
		)
		(duplicate_pad_numbers_are_jumpers no)
		(fp_line
			(start 0.299974 -0.150114)
			(end -0.299974 -0.150114)
			(stroke
				(width 0.1)
				(type default)
			)
			(layer "B.Fab")
		)
		(fp_line
			(start -0.299974 -0.150114)
			(end -0.299974 0.150114)
			(stroke
				(width 0.1)
				(type default)
			)
			(layer "B.Fab")
		)
		(fp_line
			(start 0.299974 0.150114)
			(end 0.299974 -0.150114)
			(stroke
				(width 0.1)
				(type default)
			)
			(layer "B.Fab")
		)
		(fp_line
			(start -0.299974 0.150114)
			(end 0.299974 0.150114)
			(stroke
				(width 0.1)
				(type default)
			)
			(layer "B.Fab")
		)
		(pad "1" smd rect
			(at 0.2667 0 270)
			(size 0.3048 0.381)
			(layers "B.Cu" "B.Mask" "B.Paste")
			(net "P1V25_PEX3")
		)
		(pad "2" smd rect
			(at -0.2667 0 270)
			(size 0.3048 0.381)
			(layers "B.Cu" "B.Mask" "B.Paste")
			(net "GND")
		)
	)
	(footprint ""
		(layer "B.Cu")
		(at 299.449744 -296.37482)
		(property "Reference" "C1675"
			(at 0 0 0)
			(layer "B.SilkS")
			(hide yes)
			(effects
				(font
					(size 1.27 1.27)
				)
				(justify mirror)
			)
		)
		(property "Value" ""
			(at 0 0 0)
			(layer "B.Fab")
			(effects
				(font
					(size 1.27 1.27)
				)
				(justify mirror)
			)
		)
		(duplicate_pad_numbers_are_jumpers no)
		(fp_line
			(start -0.299974 -0.150114)
			(end -0.299974 0.150114)
			(stroke
				(width 0.1)
				(type default)
			)
			(layer "B.Fab")
		)
		(fp_line
			(start -0.299974 0.150114)
			(end 0.299974 0.150114)
			(stroke
				(width 0.1)
				(type default)
			)
			(layer "B.Fab")
		)
		(fp_line
			(start 0.299974 -0.150114)
			(end -0.299974 -0.150114)
			(stroke
				(width 0.1)
				(type default)
			)
			(layer "B.Fab")
		)
		(fp_line
			(start 0.299974 0.150114)
			(end 0.299974 -0.150114)
			(stroke
				(width 0.1)
				(type default)
			)
			(layer "B.Fab")
		)
		(pad "1" smd rect
			(at 0.2667 0 180)
			(size 0.3048 0.381)
			(layers "B.Cu" "B.Mask" "B.Paste")
			(net "P0V8_SERDES_VDDA_PEX2")
		)
		(pad "2" smd rect
			(at -0.2667 0 180)
			(size 0.3048 0.381)
			(layers "B.Cu" "B.Mask" "B.Paste")
			(net "GND")
		)
	)
	(footprint ""
		(layer "B.Cu")
		(at 41.538906 -288.774886 90)
		(property "Reference" "R6157"
			(at 0 0 90)
			(layer "B.SilkS")
			(hide yes)
			(effects
				(font
					(size 1.27 1.27)
				)
				(justify mirror)
			)
		)
		(property "Value" ""
			(at 0 0 90)
			(layer "B.Fab")
			(effects
				(font
					(size 1.27 1.27)
				)
				(justify mirror)
			)
		)
		(duplicate_pad_numbers_are_jumpers no)
		(fp_line
			(start 0.7874 -0.4064)
			(end -0.7874 -0.4064)
			(stroke
				(width 0.1524)
				(type default)
			)
			(layer "B.SilkS")
		)
		(fp_line
			(start -0.7874 -0.4064)
			(end -0.7874 0.4064)
			(stroke
				(width 0.1524)
				(type default)
			)
			(layer "B.SilkS")
		)
		(fp_line
			(start 0.7874 0.4064)
			(end 0.7874 -0.4064)
			(stroke
				(width 0.1524)
				(type default)
			)
			(layer "B.SilkS")
		)
		(fp_line
			(start -0.7874 0.4064)
			(end 0.7874 0.4064)
			(stroke
				(width 0.1524)
				(type default)
			)
			(layer "B.SilkS")
		)
		(fp_line
			(start 0.67945 -0.305054)
			(end 0.12065 -0.305054)
			(stroke
				(width 0.1)
				(type default)
			)
			(layer "B.Fab")
		)
		(fp_line
			(start 0.12065 -0.305054)
			(end 0.12065 -0.2794)
			(stroke
				(width 0.1)
				(type default)
			)
			(layer "B.Fab")
		)
		(fp_line
			(start -0.12065 -0.3048)
			(end -0.67945 -0.3048)
			(stroke
				(width 0.1)
				(type default)
			)
			(layer "B.Fab")
		)
		(fp_line
			(start -0.67945 -0.3048)
			(end -0.67945 0.3048)
			(stroke
				(width 0.1)
				(type default)
			)
			(layer "B.Fab")
		)
		(fp_line
			(start 0.12065 -0.2794)
			(end -0.12065 -0.2794)
			(stroke
				(width 0.1)
				(type default)
			)
			(layer "B.Fab")
		)
		(fp_line
			(start -0.12065 -0.2794)
			(end -0.12065 -0.3048)
			(stroke
				(width 0.1)
				(type default)
			)
			(layer "B.Fab")
		)
		(fp_line
			(start 0.12065 0.2794)
			(end 0.12065 0.3048)
			(stroke
				(width 0.1)
				(type default)
			)
			(layer "B.Fab")
		)
		(fp_line
			(start -0.120396 0.2794)
			(end 0.12065 0.2794)
			(stroke
				(width 0.1)
				(type default)
			)
			(layer "B.Fab")
		)
		(fp_line
			(start 0.67945 0.3048)
			(end 0.67945 -0.305054)
			(stroke
				(width 0.1)
				(type default)
			)
			(layer "B.Fab")
		)
		(fp_line
			(start 0.12065 0.3048)
			(end 0.67945 0.3048)
			(stroke
				(width 0.1)
				(type default)
			)
			(layer "B.Fab")
		)
		(fp_line
			(start -0.120396 0.3048)
			(end -0.120396 0.2794)
			(stroke
				(width 0.1)
				(type default)
			)
			(layer "B.Fab")
		)
		(fp_line
			(start -0.67945 0.3048)
			(end -0.120396 0.3048)
			(stroke
				(width 0.1)
				(type default)
			)
			(layer "B.Fab")
		)
		(pad "1" smd circle
			(at 0.40005 0 270)
			(size 0 0)
			(layers "B.Cu" "B.Mask" "B.Paste")
			(net "SPI_PEX0_CS_N")
		)
		(pad "2" smd circle
			(at -0.40005 0 270)
			(size 0 0)
			(layers "B.Cu" "B.Mask" "B.Paste")
			(net "P1V8_PEX")
		)
	)
	(footprint ""
		(layer "B.Cu")
		(at 62.499748 -303.499774 -90)
		(property "Reference" "C2907"
			(at 0 0 90)
			(layer "B.SilkS")
			(hide yes)
			(effects
				(font
					(size 1.27 1.27)
				)
				(justify mirror)
			)
		)
		(property "Value" ""
			(at 0 0 90)
			(layer "B.Fab")
			(effects
				(font
					(size 1.27 1.27)
				)
				(justify mirror)
			)
		)
		(duplicate_pad_numbers_are_jumpers no)
		(fp_line
			(start -0.299974 0.150114)
			(end 0.299974 0.150114)
			(stroke
				(width 0.1)
				(type default)
			)
			(layer "B.Fab")
		)
		(fp_line
			(start 0.299974 0.150114)
			(end 0.299974 -0.150114)
			(stroke
				(width 0.1)
				(type default)
			)
			(layer "B.Fab")
		)
		(fp_line
			(start -0.299974 -0.150114)
			(end -0.299974 0.150114)
			(stroke
				(width 0.1)
				(type default)
			)
			(layer "B.Fab")
		)
		(fp_line
			(start 0.299974 -0.150114)
			(end -0.299974 -0.150114)
			(stroke
				(width 0.1)
				(type default)
			)
			(layer "B.Fab")
		)
		(pad "1" smd rect
			(at 0.2667 0 90)
			(size 0.3048 0.381)
			(layers "B.Cu" "B.Mask" "B.Paste")
			(net "P1V25_PEX0")
		)
		(pad "2" smd rect
			(at -0.2667 0 90)
			(size 0.3048 0.381)
			(layers "B.Cu" "B.Mask" "B.Paste")
			(net "GND")
		)
	)
)
